# BASEBOARD_FAB2 (Tioga Pass) — schematic netlist excerpt (pin names and nets, part order shuffled) for the footprints in the layout excerpt that follows; sources: Cadence DE-HDL packaged netlist, KiCad conversion of Wiwynn_Tioga_Pass_MB.brd

R25W88  RES  22.1 1.0% CHIP  pkg 0402  page 147 : A = RMII_BMC_SPRNGVLLE_TXEN_R ; B = RMII_BMC_PCH_SPRNGVLLE_TXEN
R7F21  RES  0.0 5% CHIP  pkg 0402  page 215 : A = FM_PVDDQ_ABC_EN ; B = VR_PVDDQ_ABC_VREN
C6D6  CAP_A  22.0UF 4V 20% X6S  pkg 0603V  page 42 : A = PVCCIO_CPU0 ; B = GND

(kicad_pcb
	(version 20260206)
	(generator "pcbnew")
	(generator_version "10.0")
	(general
		(thickness 1.6)
		(legacy_teardrops no)
	)
	(paper "A4")
	(title_block
		(title "Wiwynn_Tioga_Pass_MB.brd")
		(comment 1 "Tioga Pass / footprints 1686-1688 of 4770")
	)
	(layers
		(0 "F.Cu" signal "TOP")
		(4 "In1.Cu" signal "L2GND")
		(6 "In2.Cu" signal "L3")
		(8 "In3.Cu" signal "L4GND")
		(10 "In4.Cu" signal "L5")
		(12 "In5.Cu" signal "L6GND")
		(14 "In6.Cu" signal "L7VCC")
		(16 "In7.Cu" signal "L8VCC")
		(18 "In8.Cu" signal "L9GND")
		(20 "In9.Cu" signal "L10")
		(22 "In10.Cu" signal "L11GND")
		(24 "In11.Cu" signal "L12")
		(26 "In12.Cu" signal "L13GND")
		(2 "B.Cu" signal "BOTTOM")
		(9 "F.Adhes" user "F.Adhesive")
		(11 "B.Adhes" user "B.Adhesive")
		(13 "F.Paste" user "Package Geometry/Pastemask Top")
		(15 "B.Paste" user "Package Geometry/Pastemask Bottom")
		(5 "F.SilkS" user "Ref Des/Silkscreen Top")
		(7 "B.SilkS" user "Ref Des/Silkscreen Bottom")
		(1 "F.Mask" user "Board Geometry/Soldermask Top")
		(3 "B.Mask" user "Board Geometry/Soldermask Bottom")
		(17 "Dwgs.User" user "User.Drawings")
		(19 "Cmts.User" user "User.Comments")
		(21 "Eco1.User" user "User.Eco1")
		(23 "Eco2.User" user "User.Eco2")
		(25 "Edge.Cuts" user "Board Geometry/Outline")
		(27 "Margin" user)
		(31 "F.CrtYd" user "Package Geometry/Place Bound Top")
		(29 "B.CrtYd" user "Package Geometry/Place Bound Bottom")
		(35 "F.Fab" user "Ref Des/Assembly Top")
		(33 "B.Fab" user "Ref Des/Assembly Bottom")
	)
	(footprint ""
		(layer "F.Cu")
		(at 406.908 -23.0505)
		(property "Reference" "R25W88"
			(at -0.8382 -0.67818 0)
			(unlocked yes)
			(layer "F.SilkS")
			(effects
				(font
					(size 0.4064 0.254)
					(thickness 0.1524)
				)
				(justify left)
			)
		)
		(property "Value" ""
			(at 0 0 0)
			(layer "F.Fab")
			(effects
				(font
					(size 1.27 1.27)
				)
			)
		)
		(duplicate_pad_numbers_are_jumpers no)
		(fp_poly
			(pts
				(xy -0.2794 -0.1016) (xy 0.2794 -0.1016) (xy 0.2794 0.9906) (xy -0.2794 0.9906)
			)
			(stroke
				(width 0)
				(type default)
			)
			(fill no)
			(layer "F.CrtYd")
		)
		(fp_line
			(start -0.2794 -0.1016)
			(end -0.2794 0.9906)
			(stroke
				(width 0.1)
				(type default)
			)
			(layer "F.Fab")
		)
		(fp_line
			(start -0.2794 0.9906)
			(end 0.2794 0.9906)
			(stroke
				(width 0.1)
				(type default)
			)
			(layer "F.Fab")
		)
		(fp_line
			(start 0.2794 -0.1016)
			(end -0.2794 -0.1016)
			(stroke
				(width 0.1)
				(type default)
			)
			(layer "F.Fab")
		)
		(fp_line
			(start 0.2794 0.9906)
			(end 0.2794 -0.1016)
			(stroke
				(width 0.1)
				(type default)
			)
			(layer "F.Fab")
		)
		(pad "1" smd rect
			(at 0 0)
			(size 0.508 0.508)
			(layers "F.Cu" "F.Mask" "F.Paste")
			(net "RMII_BMC_SPRNGVLLE_TXEN_R")
		)
		(pad "2" smd rect
			(at 0 0.889)
			(size 0.508 0.508)
			(layers "F.Cu" "F.Mask" "F.Paste")
			(net "RMII_BMC_PCH_SPRNGVLLE_TXEN")
		)
		(zone
			(layer "F.Cu")
			(hatch none 0.5)
			(connect_pads
				(clearance 0)
			)
			(min_thickness 0.25)
			(keepout
				(tracks allowed)
				(vias not_allowed)
				(pads allowed)
				(copperpour not_allowed)
				(footprints allowed)
			)
			(placement
				(enabled no)
				(sheetname "")
			)
			(fill
				(thermal_gap 0.5)
				(thermal_bridge_width 0.5)
				(island_removal_mode 0)
			)
			(polygon
				(pts
					(xy 406.654 -22.7965) (xy 407.162 -22.7965) (xy 407.162 -22.4155) (xy 406.654 -22.4155)
				)
			)
		)
		(zone
			(layer "F.Cu")
			(hatch none 0.5)
			(connect_pads
				(clearance 0)
			)
			(min_thickness 0.25)
			(keepout
				(tracks not_allowed)
				(vias allowed)
				(pads allowed)
				(copperpour not_allowed)
				(footprints allowed)
			)
			(placement
				(enabled no)
				(sheetname "")
			)
			(fill
				(thermal_gap 0.5)
				(thermal_bridge_width 0.5)
				(island_removal_mode 0)
			)
			(polygon
				(pts
					(xy 406.654 -22.4155) (xy 407.162 -22.4155) (xy 407.162 -22.7965) (xy 406.654 -22.7965)
				)
			)
		)
	)
	(footprint ""
		(layer "F.Cu")
		(at 278.427434 -77.382116)
		(property "Reference" "C6D6"
			(at 0 0 0)
			(layer "F.SilkS")
			(hide yes)
			(effects
				(font
					(size 1.27 1.27)
				)
			)
		)
		(property "Value" ""
			(at 0 0 0)
			(layer "F.Fab")
			(effects
				(font
					(size 1.27 1.27)
				)
			)
		)
		(duplicate_pad_numbers_are_jumpers no)
		(fp_poly
			(pts
				(xy -0.4953 -0.2032) (xy 0.4953 -0.2032) (xy 0.4953 1.6002) (xy -0.4953 1.6002)
			)
			(stroke
				(width 0)
				(type default)
			)
			(fill no)
			(layer "F.CrtYd")
		)
		(fp_line
			(start -0.4953 -0.2032)
			(end 0.4953 -0.2032)
			(stroke
				(width 0.1)
				(type default)
			)
			(layer "F.Fab")
		)
		(fp_line
			(start -0.4953 1.6002)
			(end -0.4953 -0.2032)
			(stroke
				(width 0.1)
				(type default)
			)
			(layer "F.Fab")
		)
		(fp_line
			(start 0.4953 -0.2032)
			(end 0.4953 1.6002)
			(stroke
				(width 0.1)
				(type default)
			)
			(layer "F.Fab")
		)
		(fp_line
			(start 0.4953 1.6002)
			(end -0.4953 1.6002)
			(stroke
				(width 0.1)
				(type default)
			)
			(layer "F.Fab")
		)
		(pad "1" smd rect
			(at 0 0)
			(size 0.762 0.889)
			(layers "F.Cu" "F.Mask" "F.Paste")
			(net "PVCCIO_CPU0")
		)
		(pad "2" smd rect
			(at 0 1.397)
			(size 0.762 0.889)
			(layers "F.Cu" "F.Mask" "F.Paste")
			(net "GND")
		)
		(zone
			(layer "F.Cu")
			(hatch none 0.5)
			(connect_pads
				(clearance 0)
			)
			(min_thickness 0.25)
			(keepout
				(tracks not_allowed)
				(vias allowed)
				(pads allowed)
				(copperpour not_allowed)
				(footprints allowed)
			)
			(placement
				(enabled no)
				(sheetname "")
			)
			(fill
				(thermal_gap 0.5)
				(thermal_bridge_width 0.5)
				(island_removal_mode 0)
			)
			(polygon
				(pts
					(xy 278.046434 -76.937616) (xy 278.808434 -76.937616) (xy 278.808434 -76.429616) (xy 278.046434 -76.429616)
				)
			)
		)
	)
	(footprint ""
		(layer "F.Cu")
		(at 343.67216 -21.78812 -90)
		(property "Reference" "R7F21"
			(at -0.8382 -0.67818 270)
			(unlocked yes)
			(layer "F.SilkS")
			(effects
				(font
					(size 0.4064 0.254)
					(thickness 0.1524)
				)
				(justify left)
			)
		)
		(property "Value" ""
			(at 0 0 270)
			(layer "F.Fab")
			(effects
				(font
					(size 1.27 1.27)
				)
			)
		)
		(duplicate_pad_numbers_are_jumpers no)
		(fp_poly
			(pts
				(xy -0.2794 -0.1016) (xy 0.2794 -0.1016) (xy 0.2794 0.9906) (xy -0.2794 0.9906)
			)
			(stroke
				(width 0)
				(type default)
			)
			(fill no)
			(layer "F.CrtYd")
		)
		(fp_line
			(start -0.2794 0.9906)
			(end 0.2794 0.9906)
			(stroke
				(width 0.1)
				(type default)
			)
			(layer "F.Fab")
		)
		(fp_line
			(start 0.2794 0.9906)
			(end 0.2794 -0.1016)
			(stroke
				(width 0.1)
				(type default)
			)
			(layer "F.Fab")
		)
		(fp_line
			(start -0.2794 -0.1016)
			(end -0.2794 0.9906)
			(stroke
				(width 0.1)
				(type default)
			)
			(layer "F.Fab")
		)
		(fp_line
			(start 0.2794 -0.1016)
			(end -0.2794 -0.1016)
			(stroke
				(width 0.1)
				(type default)
			)
			(layer "F.Fab")
		)
		(pad "1" smd rect
			(at 0 0 270)
			(size 0.508 0.508)
			(layers "F.Cu" "F.Mask" "F.Paste")
			(net "FM_PVDDQ_ABC_EN")
		)
		(pad "2" smd rect
			(at 0 0.889 270)
			(size 0.508 0.508)
			(layers "F.Cu" "F.Mask" "F.Paste")
			(net "VR_PVDDQ_ABC_VREN")
		)
		(zone
			(layer "F.Cu")
			(hatch none 0.5)
			(connect_pads
				(clearance 0)
			)
			(min_thickness 0.25)
			(keepout
				(tracks not_allowed)
				(vias allowed)
				(pads allowed)
				(copperpour not_allowed)
				(footprints allowed)
			)
			(placement
				(enabled no)
				(sheetname "")
			)
			(fill
				(thermal_gap 0.5)
				(thermal_bridge_width 0.5)
				(island_removal_mode 0)
			)
			(polygon
				(pts
					(xy 343.03716 -22.04212) (xy 343.03716 -21.53412) (xy 343.41816 -21.53412) (xy 343.41816 -22.04212)
				)
			)
		)
		(zone
			(layer "F.Cu")
			(hatch none 0.5)
			(connect_pads
				(clearance 0)
			)
			(min_thickness 0.25)
			(keepout
				(tracks allowed)
				(vias not_allowed)
				(pads allowed)
				(copperpour not_allowed)
				(footprints allowed)
			)
			(placement
				(enabled no)
				(sheetname "")
			)
			(fill
				(thermal_gap 0.5)
				(thermal_bridge_width 0.5)
				(island_removal_mode 0)
			)
			(polygon
				(pts
					(xy 343.41816 -22.04212) (xy 343.41816 -21.53412) (xy 343.03716 -21.53412) (xy 343.03716 -22.04212)
				)
			)
		)
	)
)
